# T6G (Grand Teton) — schematic netlist excerpt (pin names and nets, part order shuffled) for the footprints in the layout excerpt that follows; sources: Cadence DE-HDL packaged netlist, KiCad conversion of 04192023_DAF0TMB3IC0_F0TG_MB_C_brd_V02_OCP.brd

PR110  Q_RES  5.6 1% CHIP  pkg 0402LF  page 206 : A = SW_PVDDIO_P0_BOOT3 ; B = SW_PVDDIO_P0_BOOT3_R
PR6630  Q_RES  1.5 1% EMPTY  pkg 0402LF  page 365 : A = SW_P0V9_RETIMER_CPU1_SW2_RC ; B = GND

(kicad_pcb
	(version 20260206)
	(generator "pcbnew")
	(generator_version "10.0")
	(general
		(thickness 1.6)
		(legacy_teardrops no)
	)
	(paper "A4")
	(title_block
		(title "04192023_DAF0TMB3IC0_F0TG_MB_C_brd_V02_OCP.brd")
		(comment 1 "Grand Teton / footprints 3648-3649 of 8354")
	)
	(layers
		(0 "F.Cu" signal "TOP")
		(4 "In1.Cu" signal "GND")
		(6 "In2.Cu" signal "IN1")
		(8 "In3.Cu" signal "GND1")
		(10 "In4.Cu" signal "IN2")
		(12 "In5.Cu" signal "GND2")
		(14 "In6.Cu" signal "IN3")
		(16 "In7.Cu" signal "GND3")
		(18 "In8.Cu" signal "VCC")
		(20 "In9.Cu" signal "VCC1")
		(22 "In10.Cu" signal "GND4")
		(24 "In11.Cu" signal "IN4")
		(26 "In12.Cu" signal "GND5")
		(28 "In13.Cu" signal "IN5")
		(30 "In14.Cu" signal "GND6")
		(32 "In15.Cu" signal "IN6")
		(34 "In16.Cu" signal "GND7")
		(2 "B.Cu" signal "BOTTOM")
		(9 "F.Adhes" user "F.Adhesive")
		(11 "B.Adhes" user "B.Adhesive")
		(13 "F.Paste" user "Package Geometry/Pastemask Top")
		(15 "B.Paste" user "Package Geometry/Pastemask Bottom")
		(5 "F.SilkS" user "Ref Des/Silkscreen Top")
		(7 "B.SilkS" user "Ref Des/Silkscreen Bottom")
		(1 "F.Mask" user "Board Geometry/Soldermask Top")
		(3 "B.Mask" user "Board Geometry/Soldermask Bottom")
		(17 "Dwgs.User" user "User.Drawings")
		(19 "Cmts.User" user "User.Comments")
		(21 "Eco1.User" user "User.Eco1")
		(23 "Eco2.User" user "User.Eco2")
		(25 "Edge.Cuts" user "Board Geometry/Outline")
		(27 "Margin" user)
		(31 "F.CrtYd" user "Package Geometry/Place Bound Top")
		(29 "B.CrtYd" user "Package Geometry/Place Bound Bottom")
		(35 "F.Fab" user "Ref Des/Assembly Top")
		(33 "B.Fab" user "Ref Des/Assembly Bottom")
	)
	(footprint ""
		(layer "F.Cu")
		(at 21.43887 -387.30809 90)
		(property "Reference" "PR6630"
			(at 0 0 90)
			(layer "F.SilkS")
			(hide yes)
			(effects
				(font
					(size 1.27 1.27)
				)
			)
		)
		(property "Value" ""
			(at 0 0 90)
			(layer "F.Fab")
			(effects
				(font
					(size 1.27 1.27)
				)
			)
		)
		(duplicate_pad_numbers_are_jumpers no)
		(fp_line
			(start 0.7874 -0.4064)
			(end 0.7874 0.4064)
			(stroke
				(width 0.1524)
				(type default)
			)
			(layer "F.SilkS")
		)
		(fp_line
			(start -0.7874 -0.4064)
			(end 0.7874 -0.4064)
			(stroke
				(width 0.1524)
				(type default)
			)
			(layer "F.SilkS")
		)
		(fp_line
			(start 0.7874 0.4064)
			(end -0.7874 0.4064)
			(stroke
				(width 0.1524)
				(type default)
			)
			(layer "F.SilkS")
		)
		(fp_line
			(start -0.7874 0.4064)
			(end -0.7874 -0.4064)
			(stroke
				(width 0.1524)
				(type default)
			)
			(layer "F.SilkS")
		)
		(fp_line
			(start -0.12065 -0.305054)
			(end -0.12065 -0.2794)
			(stroke
				(width 0.1)
				(type default)
			)
			(layer "F.Fab")
		)
		(fp_line
			(start -0.67945 -0.305054)
			(end -0.12065 -0.305054)
			(stroke
				(width 0.1)
				(type default)
			)
			(layer "F.Fab")
		)
		(fp_line
			(start 0.67945 -0.3048)
			(end 0.67945 0.3048)
			(stroke
				(width 0.1)
				(type default)
			)
			(layer "F.Fab")
		)
		(fp_line
			(start 0.12065 -0.3048)
			(end 0.67945 -0.3048)
			(stroke
				(width 0.1)
				(type default)
			)
			(layer "F.Fab")
		)
		(fp_line
			(start 0.12065 -0.2794)
			(end 0.12065 -0.3048)
			(stroke
				(width 0.1)
				(type default)
			)
			(layer "F.Fab")
		)
		(fp_line
			(start -0.12065 -0.2794)
			(end 0.12065 -0.2794)
			(stroke
				(width 0.1)
				(type default)
			)
			(layer "F.Fab")
		)
		(fp_line
			(start 0.120396 0.2794)
			(end -0.12065 0.2794)
			(stroke
				(width 0.1)
				(type default)
			)
			(layer "F.Fab")
		)
		(fp_line
			(start -0.12065 0.2794)
			(end -0.12065 0.3048)
			(stroke
				(width 0.1)
				(type default)
			)
			(layer "F.Fab")
		)
		(fp_line
			(start 0.67945 0.3048)
			(end 0.120396 0.3048)
			(stroke
				(width 0.1)
				(type default)
			)
			(layer "F.Fab")
		)
		(fp_line
			(start 0.120396 0.3048)
			(end 0.120396 0.2794)
			(stroke
				(width 0.1)
				(type default)
			)
			(layer "F.Fab")
		)
		(fp_line
			(start -0.12065 0.3048)
			(end -0.67945 0.3048)
			(stroke
				(width 0.1)
				(type default)
			)
			(layer "F.Fab")
		)
		(fp_line
			(start -0.67945 0.3048)
			(end -0.67945 -0.305054)
			(stroke
				(width 0.1)
				(type default)
			)
			(layer "F.Fab")
		)
		(pad "1" smd circle
			(at -0.40005 0 90)
			(size 0 0)
			(layers "F.Cu" "F.Mask" "F.Paste")
			(net "SW_P0V9_RETIMER_CPU1_SW2_RC")
		)
		(pad "2" smd circle
			(at 0.40005 0 90)
			(size 0 0)
			(layers "F.Cu" "F.Mask" "F.Paste")
			(net "GND")
		)
	)
	(footprint ""
		(layer "F.Cu")
		(at 284.461712 -351.368106 90)
		(property "Reference" "PR110"
			(at 0 0 90)
			(layer "F.SilkS")
			(hide yes)
			(effects
				(font
					(size 1.27 1.27)
				)
			)
		)
		(property "Value" ""
			(at 0 0 90)
			(layer "F.Fab")
			(effects
				(font
					(size 1.27 1.27)
				)
			)
		)
		(duplicate_pad_numbers_are_jumpers no)
		(fp_line
			(start 0.7874 -0.4064)
			(end 0.7874 0.4064)
			(stroke
				(width 0.1524)
				(type default)
			)
			(layer "F.SilkS")
		)
		(fp_line
			(start -0.7874 -0.4064)
			(end 0.7874 -0.4064)
			(stroke
				(width 0.1524)
				(type default)
			)
			(layer "F.SilkS")
		)
		(fp_line
			(start 0.7874 0.4064)
			(end -0.7874 0.4064)
			(stroke
				(width 0.1524)
				(type default)
			)
			(layer "F.SilkS")
		)
		(fp_line
			(start -0.7874 0.4064)
			(end -0.7874 -0.4064)
			(stroke
				(width 0.1524)
				(type default)
			)
			(layer "F.SilkS")
		)
		(fp_line
			(start -0.12065 -0.305054)
			(end -0.12065 -0.2794)
			(stroke
				(width 0.1)
				(type default)
			)
			(layer "F.Fab")
		)
		(fp_line
			(start -0.67945 -0.305054)
			(end -0.12065 -0.305054)
			(stroke
				(width 0.1)
				(type default)
			)
			(layer "F.Fab")
		)
		(fp_line
			(start 0.67945 -0.3048)
			(end 0.67945 0.3048)
			(stroke
				(width 0.1)
				(type default)
			)
			(layer "F.Fab")
		)
		(fp_line
			(start 0.12065 -0.3048)
			(end 0.67945 -0.3048)
			(stroke
				(width 0.1)
				(type default)
			)
			(layer "F.Fab")
		)
		(fp_line
			(start 0.12065 -0.2794)
			(end 0.12065 -0.3048)
			(stroke
				(width 0.1)
				(type default)
			)
			(layer "F.Fab")
		)
		(fp_line
			(start -0.12065 -0.2794)
			(end 0.12065 -0.2794)
			(stroke
				(width 0.1)
				(type default)
			)
			(layer "F.Fab")
		)
		(fp_line
			(start 0.120396 0.2794)
			(end -0.12065 0.2794)
			(stroke
				(width 0.1)
				(type default)
			)
			(layer "F.Fab")
		)
		(fp_line
			(start -0.12065 0.2794)
			(end -0.12065 0.3048)
			(stroke
				(width 0.1)
				(type default)
			)
			(layer "F.Fab")
		)
		(fp_line
			(start 0.67945 0.3048)
			(end 0.120396 0.3048)
			(stroke
				(width 0.1)
				(type default)
			)
			(layer "F.Fab")
		)
		(fp_line
			(start 0.120396 0.3048)
			(end 0.120396 0.2794)
			(stroke
				(width 0.1)
				(type default)
			)
			(layer "F.Fab")
		)
		(fp_line
			(start -0.12065 0.3048)
			(end -0.67945 0.3048)
			(stroke
				(width 0.1)
				(type default)
			)
			(layer "F.Fab")
		)
		(fp_line
			(start -0.67945 0.3048)
			(end -0.67945 -0.305054)
			(stroke
				(width 0.1)
				(type default)
			)
			(layer "F.Fab")
		)
		(pad "1" smd circle
			(at -0.40005 0 90)
			(size 0 0)
			(layers "F.Cu" "F.Mask" "F.Paste")
			(net "SW_PVDDIO_P0_BOOT3")
		)
		(pad "2" smd circle
			(at 0.40005 0 90)
			(size 0 0)
			(layers "F.Cu" "F.Mask" "F.Paste")
			(net "SW_PVDDIO_P0_BOOT3_R")
		)
	)
)
